(kicad_pcb
	(version 20260206)
	(generator "pcbnew")
	(generator_version "10.0")
	(general
		(thickness 1.6)
		(legacy_teardrops no)
	)
	(paper "A4")
	(title_block
		(title "panther-plus-userver — 13130-1b_20150205.brd")
		(comment 1 "Honey Badger (Wiwynn) / footprint 1214 of 1509 (DIMM3), pads 16-22 of 210")
	)
	(layers
		(0 "F.Cu" signal "TOP")
		(4 "In1.Cu" signal "L2")
		(6 "In2.Cu" signal "L3")
		(8 "In3.Cu" signal "L4")
		(10 "In4.Cu" signal "L5")
		(12 "In5.Cu" signal "L6")
		(14 "In6.Cu" signal "L7")
		(16 "In7.Cu" signal "L8")
		(18 "In8.Cu" signal "L9")
		(20 "In9.Cu" signal "L10")
		(22 "In10.Cu" signal "L11")
		(2 "B.Cu" signal "BOTTOM")
		(9 "F.Adhes" user "F.Adhesive")
		(11 "B.Adhes" user "B.Adhesive")
		(13 "F.Paste" user "Package Geometry/Pastemask Top")
		(15 "B.Paste" user "Package Geometry/Pastemask Bottom")
		(5 "F.SilkS" user "Ref Des/Silkscreen Top")
		(7 "B.SilkS" user "Ref Des/Silkscreen Bottom")
		(1 "F.Mask" user "Board Geometry/Soldermask Top")
		(3 "B.Mask" user "Board Geometry/Soldermask Bottom")
		(17 "Dwgs.User" user "User.Drawings")
		(19 "Cmts.User" user "User.Comments")
		(21 "Eco1.User" user "User.Eco1")
		(23 "Eco2.User" user "User.Eco2")
		(25 "Edge.Cuts" user "Board Geometry/Outline")
		(27 "Margin" user)
		(31 "F.CrtYd" user "Package Geometry/Place Bound Top")
		(29 "B.CrtYd" user "Package Geometry/Place Bound Bottom")
		(35 "F.Fab" user "Ref Des/Assembly Top")
		(33 "B.Fab" user "Ref Des/Assembly Bottom")
	)
	(footprint ""
		(layer "B.Cu")
		(at 159.999934 -5.790692)
		(property "Reference" "DIMM3"
			(at 0 0 0)
			(layer "B.SilkS")
			(hide yes)
			(effects
				(font
					(size 1.27 1.27)
				)
				(justify mirror)
			)
		)
		(property "Value" "DDR3-204P-142-COLAY-1-GP-U"
			(at 41.312338 -16.676878 0)
			(unlocked yes)
			(layer "B.Fab")
			(hide yes)
			(effects
				(font
					(size 1.016 1.016)
					(thickness 0.1524)
				)
				(justify mirror)
			)
		)
		(property "Device Type" "AS0A626-J8R6-7H-COLAY-1"
			(at 41.312338 -18.200878 0)
			(unlocked yes)
			(layer "B.Fab")
			(hide yes)
			(effects
				(font
					(size 1.016 1.016)
					(thickness 0.1524)
				)
				(justify mirror)
			)
		)
		(duplicate_pad_numbers_are_jumpers no)
		(pad "14" smd custom
			(at -27.750008 4.100068 180)
			(size 0.1143 0.1143)
			(layers "B.Cu" "B.Mask" "B.Paste")
			(net "GND")
			(options
				(clearance outline)
				(anchor circle)
			)
			(primitives
				(gr_poly
					(pts
						(xy 0 -0.9017) (xy -0.03175 -0.89916) (xy -0.0635 -0.889) (xy -0.09144 -0.87376) (xy -0.11684 -0.85344)
						(xy -0.13716 -0.82804) (xy -0.1524 -0.8001) (xy -0.16256 -0.76835) (xy -0.1651 -0.7366) (xy -0.1651 0.13462)
						(xy -0.17272 0.14224) (xy -0.19812 0.1778) (xy -0.2032 0.18796) (xy -0.20701 0.19685) (xy -0.21209 0.20701)
						(xy -0.2159 0.21717) (xy -0.21844 0.22733) (xy -0.22225 0.23876) (xy -0.22352 0.24892) (xy -0.22606 0.25908)
						(xy -0.22733 0.27051) (xy -0.22733 0.28067) (xy -0.2286 0.2921) (xy -0.22733 0.30353) (xy -0.22733 0.31369)
						(xy -0.22606 0.32512) (xy -0.22352 0.33528) (xy -0.22225 0.34544) (xy -0.21844 0.35687) (xy -0.2159 0.36703)
						(xy -0.21209 0.37719) (xy -0.20701 0.38735) (xy -0.2032 0.39624) (xy -0.19812 0.4064) (xy -0.17272 0.44196)
						(xy -0.1651 0.44958) (xy -0.1651 0.7366) (xy -0.16256 0.76835) (xy -0.1524 0.8001) (xy -0.13716 0.82804)
						(xy -0.11684 0.85344) (xy -0.09144 0.87376) (xy -0.0635 0.889) (xy -0.03175 0.89916) (xy 0 0.9017)
						(xy 0.03175 0.89916) (xy 0.0635 0.889) (xy 0.09144 0.87376) (xy 0.11684 0.85344) (xy 0.13716 0.82804)
						(xy 0.1524 0.8001) (xy 0.16256 0.76835) (xy 0.1651 0.7366) (xy 0.1651 0.44958) (xy 0.17272 0.44196)
						(xy 0.19812 0.4064) (xy 0.2032 0.39624) (xy 0.20701 0.38735) (xy 0.21209 0.37719) (xy 0.2159 0.36703)
						(xy 0.21844 0.35687) (xy 0.22225 0.34544) (xy 0.22352 0.33528) (xy 0.22606 0.32512) (xy 0.22733 0.31369)
						(xy 0.22733 0.30353) (xy 0.2286 0.2921) (xy 0.22733 0.28067) (xy 0.22733 0.27051) (xy 0.22606 0.25908)
						(xy 0.22352 0.24892) (xy 0.22225 0.23876) (xy 0.21844 0.22733) (xy 0.2159 0.21717) (xy 0.21209 0.20701)
						(xy 0.20701 0.19685) (xy 0.2032 0.18796) (xy 0.19812 0.1778) (xy 0.17272 0.14224) (xy 0.1651 0.13462)
						(xy 0.1651 -0.7366) (xy 0.16256 -0.76835) (xy 0.1524 -0.8001) (xy 0.13716 -0.82804) (xy 0.11684 -0.85344)
						(xy 0.09144 -0.87376) (xy 0.0635 -0.889) (xy 0.03175 -0.89916)
					)
					(width 0)
					(fill yes)
				)
			)
		)
		(pad "15" smd custom
			(at -27.450034 -4.100068 180)
			(size 0.1143 0.1143)
			(layers "B.Cu" "B.Mask" "B.Paste")
			(net "M_B_DQ3")
			(options
				(clearance outline)
				(anchor circle)
			)
			(primitives
				(gr_poly
					(pts
						(xy 0 -0.9017) (xy -0.03175 -0.89916) (xy -0.0635 -0.889) (xy -0.09144 -0.87376) (xy -0.11684 -0.85344)
						(xy -0.13716 -0.82804) (xy -0.1524 -0.8001) (xy -0.16256 -0.76835) (xy -0.1651 -0.7366) (xy -0.1651 -0.19685)
						(xy -0.17272 -0.18923) (xy -0.17907 -0.18034) (xy -0.18669 -0.17145) (xy -0.19177 -0.16256) (xy -0.19812 -0.15367)
						(xy -0.20828 -0.13335) (xy -0.21971 -0.10287) (xy -0.22225 -0.09271) (xy -0.22479 -0.08128) (xy -0.22606 -0.07112)
						(xy -0.2286 -0.05969) (xy -0.2286 -0.01651) (xy -0.22606 -0.00508) (xy -0.22479 0.00508) (xy -0.22225 0.01651)
						(xy -0.21971 0.02667) (xy -0.20828 0.05715) (xy -0.19812 0.07747) (xy -0.19177 0.08636) (xy -0.18669 0.09525)
						(xy -0.17907 0.10414) (xy -0.17272 0.11303) (xy -0.1651 0.12065) (xy -0.1651 0.7366) (xy -0.16256 0.76835)
						(xy -0.1524 0.8001) (xy -0.13716 0.82804) (xy -0.11684 0.85344) (xy -0.09144 0.87376) (xy -0.0635 0.889)
						(xy -0.03175 0.89916) (xy 0 0.9017) (xy 0.03175 0.89916) (xy 0.0635 0.889) (xy 0.09144 0.87376)
						(xy 0.11684 0.85344) (xy 0.13716 0.82804) (xy 0.1524 0.8001) (xy 0.16256 0.76835) (xy 0.1651 0.7366)
						(xy 0.1651 0.11938) (xy 0.17272 0.11176) (xy 0.19812 0.0762) (xy 0.2032 0.06604) (xy 0.20701 0.05715)
						(xy 0.21209 0.04699) (xy 0.2159 0.03683) (xy 0.21844 0.02667) (xy 0.22225 0.01524) (xy 0.22352 0.00508)
						(xy 0.22606 -0.00508) (xy 0.22733 -0.01651) (xy 0.22733 -0.02667) (xy 0.2286 -0.0381) (xy 0.22733 -0.04953)
						(xy 0.22733 -0.05969) (xy 0.22606 -0.07112) (xy 0.22352 -0.08128) (xy 0.22225 -0.09144) (xy 0.21844 -0.10287)
						(xy 0.2159 -0.11303) (xy 0.21209 -0.12319) (xy 0.20701 -0.13335) (xy 0.2032 -0.14224) (xy 0.19812 -0.1524)
						(xy 0.17272 -0.18796) (xy 0.1651 -0.19558) (xy 0.1651 -0.7366) (xy 0.16256 -0.76835) (xy 0.1524 -0.8001)
						(xy 0.13716 -0.82804) (xy 0.11684 -0.85344) (xy 0.09144 -0.87376) (xy 0.0635 -0.889) (xy 0.03175 -0.89916)
					)
					(width 0)
					(fill yes)
				)
			)
		)
		(pad "16" smd custom
			(at -27.15006 4.100068 180)
			(size 0.1143 0.1143)
			(layers "B.Cu" "B.Mask" "B.Paste")
			(net "M_B_DQ6")
			(options
				(clearance outline)
				(anchor circle)
			)
			(primitives
				(gr_poly
					(pts
						(xy 0 -0.9017) (xy -0.03175 -0.89916) (xy -0.0635 -0.889) (xy -0.09144 -0.87376) (xy -0.11684 -0.85344)
						(xy -0.13716 -0.82804) (xy -0.1524 -0.8001) (xy -0.16256 -0.76835) (xy -0.1651 -0.7366) (xy -0.1651 -0.11938)
						(xy -0.17272 -0.11176) (xy -0.19812 -0.0762) (xy -0.2032 -0.06604) (xy -0.20701 -0.05715) (xy -0.21209 -0.04699)
						(xy -0.2159 -0.03683) (xy -0.21844 -0.02667) (xy -0.22225 -0.01524) (xy -0.22352 -0.00508) (xy -0.22606 0.00508)
						(xy -0.22733 0.01651) (xy -0.22733 0.02667) (xy -0.2286 0.0381) (xy -0.22733 0.04953) (xy -0.22733 0.05969)
						(xy -0.22606 0.07112) (xy -0.22352 0.08128) (xy -0.22225 0.09144) (xy -0.21844 0.10287) (xy -0.2159 0.11303)
						(xy -0.21209 0.12319) (xy -0.20701 0.13335) (xy -0.2032 0.14224) (xy -0.19812 0.1524) (xy -0.17272 0.18796)
						(xy -0.1651 0.19558) (xy -0.1651 0.7366) (xy -0.16256 0.76835) (xy -0.1524 0.8001) (xy -0.13716 0.82804)
						(xy -0.11684 0.85344) (xy -0.09144 0.87376) (xy -0.0635 0.889) (xy -0.03175 0.89916) (xy 0 0.9017)
						(xy 0.03175 0.89916) (xy 0.0635 0.889) (xy 0.09144 0.87376) (xy 0.11684 0.85344) (xy 0.13716 0.82804)
						(xy 0.1524 0.8001) (xy 0.16256 0.76835) (xy 0.1651 0.7366) (xy 0.1651 0.19685) (xy 0.17272 0.18923)
						(xy 0.17907 0.18034) (xy 0.18669 0.17145) (xy 0.19177 0.16256) (xy 0.19812 0.15367) (xy 0.20828 0.13335)
						(xy 0.21971 0.10287) (xy 0.22225 0.09271) (xy 0.22479 0.08128) (xy 0.22606 0.07112) (xy 0.2286 0.05969)
						(xy 0.2286 0.01651) (xy 0.22606 0.00508) (xy 0.22479 -0.00508) (xy 0.22225 -0.01651) (xy 0.21971 -0.02667)
						(xy 0.20828 -0.05715) (xy 0.19812 -0.07747) (xy 0.19177 -0.08636) (xy 0.18669 -0.09525) (xy 0.17907 -0.10414)
						(xy 0.17272 -0.11303) (xy 0.1651 -0.12065) (xy 0.1651 -0.7366) (xy 0.16256 -0.76835) (xy 0.1524 -0.8001)
						(xy 0.13716 -0.82804) (xy 0.11684 -0.85344) (xy 0.09144 -0.87376) (xy 0.0635 -0.889) (xy 0.03175 -0.89916)
					)
					(width 0)
					(fill yes)
				)
			)
		)
		(pad "17" smd custom
			(at -26.850086 -4.100068 180)
			(size 0.1143 0.1143)
			(layers "B.Cu" "B.Mask" "B.Paste")
			(net "GND")
			(options
				(clearance outline)
				(anchor circle)
			)
			(primitives
				(gr_poly
					(pts
						(xy 0 -0.9017) (xy -0.03175 -0.89916) (xy -0.0635 -0.889) (xy -0.09144 -0.87376) (xy -0.11684 -0.85344)
						(xy -0.13716 -0.82804) (xy -0.1524 -0.8001) (xy -0.16256 -0.76835) (xy -0.1651 -0.7366) (xy -0.1651 -0.44958)
						(xy -0.17272 -0.44196) (xy -0.19812 -0.4064) (xy -0.2032 -0.39624) (xy -0.20701 -0.38735) (xy -0.21209 -0.37719)
						(xy -0.2159 -0.36703) (xy -0.21844 -0.35687) (xy -0.22225 -0.34544) (xy -0.22352 -0.33528) (xy -0.22606 -0.32512)
						(xy -0.22733 -0.31369) (xy -0.22733 -0.30353) (xy -0.2286 -0.2921) (xy -0.22733 -0.28067) (xy -0.22733 -0.27051)
						(xy -0.22606 -0.25908) (xy -0.22352 -0.24892) (xy -0.22225 -0.23876) (xy -0.21844 -0.22733) (xy -0.2159 -0.21717)
						(xy -0.21209 -0.20701) (xy -0.20701 -0.19685) (xy -0.2032 -0.18796) (xy -0.19812 -0.1778) (xy -0.17272 -0.14224)
						(xy -0.1651 -0.13462) (xy -0.1651 0.7366) (xy -0.16256 0.76835) (xy -0.1524 0.8001) (xy -0.13716 0.82804)
						(xy -0.11684 0.85344) (xy -0.09144 0.87376) (xy -0.0635 0.889) (xy -0.03175 0.89916) (xy 0 0.9017)
						(xy 0.03175 0.89916) (xy 0.0635 0.889) (xy 0.09144 0.87376) (xy 0.11684 0.85344) (xy 0.13716 0.82804)
						(xy 0.1524 0.8001) (xy 0.16256 0.76835) (xy 0.1651 0.7366) (xy 0.1651 -0.13462) (xy 0.17272 -0.14224)
						(xy 0.19812 -0.1778) (xy 0.2032 -0.18796) (xy 0.20701 -0.19685) (xy 0.21209 -0.20701) (xy 0.2159 -0.21717)
						(xy 0.21844 -0.22733) (xy 0.22225 -0.23876) (xy 0.22352 -0.24892) (xy 0.22606 -0.25908) (xy 0.22733 -0.27051)
						(xy 0.22733 -0.28067) (xy 0.2286 -0.2921) (xy 0.22733 -0.30353) (xy 0.22733 -0.31369) (xy 0.22606 -0.32512)
						(xy 0.22352 -0.33528) (xy 0.22225 -0.34544) (xy 0.21844 -0.35687) (xy 0.2159 -0.36703) (xy 0.21209 -0.37719)
						(xy 0.20701 -0.38735) (xy 0.2032 -0.39624) (xy 0.19812 -0.4064) (xy 0.17272 -0.44196) (xy 0.1651 -0.44958)
						(xy 0.1651 -0.7366) (xy 0.16256 -0.76835) (xy 0.1524 -0.8001) (xy 0.13716 -0.82804) (xy 0.11684 -0.85344)
						(xy 0.09144 -0.87376) (xy 0.0635 -0.889) (xy 0.03175 -0.89916)
					)
					(width 0)
					(fill yes)
				)
			)
		)
		(pad "18" smd custom
			(at -26.550112 4.100068 180)
			(size 0.1143 0.1143)
			(layers "B.Cu" "B.Mask" "B.Paste")
			(net "M_B_DQ7")
			(options
				(clearance outline)
				(anchor circle)
			)
			(primitives
				(gr_poly
					(pts
						(xy 0 -0.9017) (xy -0.03175 -0.89916) (xy -0.0635 -0.889) (xy -0.09144 -0.87376) (xy -0.11684 -0.85344)
						(xy -0.13716 -0.82804) (xy -0.1524 -0.8001) (xy -0.16256 -0.76835) (xy -0.1651 -0.7366) (xy -0.1651 0.13462)
						(xy -0.17272 0.14224) (xy -0.19812 0.1778) (xy -0.2032 0.18796) (xy -0.20701 0.19685) (xy -0.21209 0.20701)
						(xy -0.2159 0.21717) (xy -0.21844 0.22733) (xy -0.22225 0.23876) (xy -0.22352 0.24892) (xy -0.22606 0.25908)
						(xy -0.22733 0.27051) (xy -0.22733 0.28067) (xy -0.2286 0.2921) (xy -0.22733 0.30353) (xy -0.22733 0.31369)
						(xy -0.22606 0.32512) (xy -0.22352 0.33528) (xy -0.22225 0.34544) (xy -0.21844 0.35687) (xy -0.2159 0.36703)
						(xy -0.21209 0.37719) (xy -0.20701 0.38735) (xy -0.2032 0.39624) (xy -0.19812 0.4064) (xy -0.17272 0.44196)
						(xy -0.1651 0.44958) (xy -0.1651 0.7366) (xy -0.16256 0.76835) (xy -0.1524 0.8001) (xy -0.13716 0.82804)
						(xy -0.11684 0.85344) (xy -0.09144 0.87376) (xy -0.0635 0.889) (xy -0.03175 0.89916) (xy 0 0.9017)
						(xy 0.03175 0.89916) (xy 0.0635 0.889) (xy 0.09144 0.87376) (xy 0.11684 0.85344) (xy 0.13716 0.82804)
						(xy 0.1524 0.8001) (xy 0.16256 0.76835) (xy 0.1651 0.7366) (xy 0.1651 0.44958) (xy 0.17272 0.44196)
						(xy 0.19812 0.4064) (xy 0.2032 0.39624) (xy 0.20701 0.38735) (xy 0.21209 0.37719) (xy 0.2159 0.36703)
						(xy 0.21844 0.35687) (xy 0.22225 0.34544) (xy 0.22352 0.33528) (xy 0.22606 0.32512) (xy 0.22733 0.31369)
						(xy 0.22733 0.30353) (xy 0.2286 0.2921) (xy 0.22733 0.28067) (xy 0.22733 0.27051) (xy 0.22606 0.25908)
						(xy 0.22352 0.24892) (xy 0.22225 0.23876) (xy 0.21844 0.22733) (xy 0.2159 0.21717) (xy 0.21209 0.20701)
						(xy 0.20701 0.19685) (xy 0.2032 0.18796) (xy 0.19812 0.1778) (xy 0.17272 0.14224) (xy 0.1651 0.13462)
						(xy 0.1651 -0.7366) (xy 0.16256 -0.76835) (xy 0.1524 -0.8001) (xy 0.13716 -0.82804) (xy 0.11684 -0.85344)
						(xy 0.09144 -0.87376) (xy 0.0635 -0.889) (xy 0.03175 -0.89916)
					)
					(width 0)
					(fill yes)
				)
			)
		)
		(pad "19" smd custom
			(at -26.249884 -4.100068 180)
			(size 0.1143 0.1143)
			(layers "B.Cu" "B.Mask" "B.Paste")
			(net "M_B_DQ8")
			(options
				(clearance outline)
				(anchor circle)
			)
			(primitives
				(gr_poly
					(pts
						(xy 0 -0.9017) (xy -0.03175 -0.89916) (xy -0.0635 -0.889) (xy -0.09144 -0.87376) (xy -0.11684 -0.85344)
						(xy -0.13716 -0.82804) (xy -0.1524 -0.8001) (xy -0.16256 -0.76835) (xy -0.1651 -0.7366) (xy -0.1651 -0.19685)
						(xy -0.17272 -0.18923) (xy -0.17907 -0.18034) (xy -0.18669 -0.17145) (xy -0.19177 -0.16256) (xy -0.19812 -0.15367)
						(xy -0.20828 -0.13335) (xy -0.21971 -0.10287) (xy -0.22225 -0.09271) (xy -0.22479 -0.08128) (xy -0.22606 -0.07112)
						(xy -0.2286 -0.05969) (xy -0.2286 -0.01651) (xy -0.22606 -0.00508) (xy -0.22479 0.00508) (xy -0.22225 0.01651)
						(xy -0.21971 0.02667) (xy -0.20828 0.05715) (xy -0.19812 0.07747) (xy -0.19177 0.08636) (xy -0.18669 0.09525)
						(xy -0.17907 0.10414) (xy -0.17272 0.11303) (xy -0.1651 0.12065) (xy -0.1651 0.7366) (xy -0.16256 0.76835)
						(xy -0.1524 0.8001) (xy -0.13716 0.82804) (xy -0.11684 0.85344) (xy -0.09144 0.87376) (xy -0.0635 0.889)
						(xy -0.03175 0.89916) (xy 0 0.9017) (xy 0.03175 0.89916) (xy 0.0635 0.889) (xy 0.09144 0.87376)
						(xy 0.11684 0.85344) (xy 0.13716 0.82804) (xy 0.1524 0.8001) (xy 0.16256 0.76835) (xy 0.1651 0.7366)
						(xy 0.1651 0.11938) (xy 0.17272 0.11176) (xy 0.19812 0.0762) (xy 0.2032 0.06604) (xy 0.20701 0.05715)
						(xy 0.21209 0.04699) (xy 0.2159 0.03683) (xy 0.21844 0.02667) (xy 0.22225 0.01524) (xy 0.22352 0.00508)
						(xy 0.22606 -0.00508) (xy 0.22733 -0.01651) (xy 0.22733 -0.02667) (xy 0.2286 -0.0381) (xy 0.22733 -0.04953)
						(xy 0.22733 -0.05969) (xy 0.22606 -0.07112) (xy 0.22352 -0.08128) (xy 0.22225 -0.09144) (xy 0.21844 -0.10287)
						(xy 0.2159 -0.11303) (xy 0.21209 -0.12319) (xy 0.20701 -0.13335) (xy 0.2032 -0.14224) (xy 0.19812 -0.1524)
						(xy 0.17272 -0.18796) (xy 0.1651 -0.19558) (xy 0.1651 -0.7366) (xy 0.16256 -0.76835) (xy 0.1524 -0.8001)
						(xy 0.13716 -0.82804) (xy 0.11684 -0.85344) (xy 0.09144 -0.87376) (xy 0.0635 -0.889) (xy 0.03175 -0.89916)
					)
					(width 0)
					(fill yes)
				)
			)
		)
		(pad "20" smd custom
			(at -25.94991 4.100068 180)
			(size 0.1143 0.1143)
			(layers "B.Cu" "B.Mask" "B.Paste")
			(net "GND")
			(options
				(clearance outline)
				(anchor circle)
			)
			(primitives
				(gr_poly
					(pts
						(xy 0 -0.9017) (xy -0.03175 -0.89916) (xy -0.0635 -0.889) (xy -0.09144 -0.87376) (xy -0.11684 -0.85344)
						(xy -0.13716 -0.82804) (xy -0.1524 -0.8001) (xy -0.16256 -0.76835) (xy -0.1651 -0.7366) (xy -0.1651 -0.11938)
						(xy -0.17272 -0.11176) (xy -0.19812 -0.0762) (xy -0.2032 -0.06604) (xy -0.20701 -0.05715) (xy -0.21209 -0.04699)
						(xy -0.2159 -0.03683) (xy -0.21844 -0.02667) (xy -0.22225 -0.01524) (xy -0.22352 -0.00508) (xy -0.22606 0.00508)
						(xy -0.22733 0.01651) (xy -0.22733 0.02667) (xy -0.2286 0.0381) (xy -0.22733 0.04953) (xy -0.22733 0.05969)
						(xy -0.22606 0.07112) (xy -0.22352 0.08128) (xy -0.22225 0.09144) (xy -0.21844 0.10287) (xy -0.2159 0.11303)
						(xy -0.21209 0.12319) (xy -0.20701 0.13335) (xy -0.2032 0.14224) (xy -0.19812 0.1524) (xy -0.17272 0.18796)
						(xy -0.1651 0.19558) (xy -0.1651 0.7366) (xy -0.16256 0.76835) (xy -0.1524 0.8001) (xy -0.13716 0.82804)
						(xy -0.11684 0.85344) (xy -0.09144 0.87376) (xy -0.0635 0.889) (xy -0.03175 0.89916) (xy 0 0.9017)
						(xy 0.03175 0.89916) (xy 0.0635 0.889) (xy 0.09144 0.87376) (xy 0.11684 0.85344) (xy 0.13716 0.82804)
						(xy 0.1524 0.8001) (xy 0.16256 0.76835) (xy 0.1651 0.7366) (xy 0.1651 0.19685) (xy 0.17272 0.18923)
						(xy 0.17907 0.18034) (xy 0.18669 0.17145) (xy 0.19177 0.16256) (xy 0.19812 0.15367) (xy 0.20828 0.13335)
						(xy 0.21971 0.10287) (xy 0.22225 0.09271) (xy 0.22479 0.08128) (xy 0.22606 0.07112) (xy 0.2286 0.05969)
						(xy 0.2286 0.01651) (xy 0.22606 0.00508) (xy 0.22479 -0.00508) (xy 0.22225 -0.01651) (xy 0.21971 -0.02667)
						(xy 0.20828 -0.05715) (xy 0.19812 -0.07747) (xy 0.19177 -0.08636) (xy 0.18669 -0.09525) (xy 0.17907 -0.10414)
						(xy 0.17272 -0.11303) (xy 0.1651 -0.12065) (xy 0.1651 -0.7366) (xy 0.16256 -0.76835) (xy 0.1524 -0.8001)
						(xy 0.13716 -0.82804) (xy 0.11684 -0.85344) (xy 0.09144 -0.87376) (xy 0.0635 -0.889) (xy 0.03175 -0.89916)
					)
					(width 0)
					(fill yes)
				)
			)
		)
	)
)
